# BASEBOARD_FAB2 (Tioga Pass) — schematic netlist excerpt (pin names and nets, part order shuffled) for the footprints in the layout excerpt that follows; sources: Cadence DE-HDL packaged netlist, KiCad conversion of Wiwynn_Tioga_Pass_MB.brd

R7C25  RES  68.1K 1% EMPTY  pkg 0402  page 212 : A = VR_PVCCIO_CPU0_OCSET ; B = GND
CF16  SC22P50V2JN-4GP  5%  pkg SMD-BCG  page 215 : \1\ = VR_PVDDQ_ABC_AIREF2 ; \2\ = ISENSE_PVDDQ_ABC_PH2_IMON
R7F23  RES  33.2 1% CHIP  pkg 0402  page 215 : A = IRQ_PVDDQ_ABC_VRHOT_LVT3_R_N ; B = IRQ_PVDDQ_ABC_VRHOT_LVT3_N

(kicad_pcb
	(version 20260206)
	(generator "pcbnew")
	(generator_version "10.0")
	(general
		(thickness 1.6)
		(legacy_teardrops no)
	)
	(paper "A4")
	(title_block
		(title "Wiwynn_Tioga_Pass_MB.brd")
		(comment 1 "Tioga Pass / footprints 734-736 of 4770")
	)
	(layers
		(0 "F.Cu" signal "TOP")
		(4 "In1.Cu" signal "L2GND")
		(6 "In2.Cu" signal "L3")
		(8 "In3.Cu" signal "L4GND")
		(10 "In4.Cu" signal "L5")
		(12 "In5.Cu" signal "L6GND")
		(14 "In6.Cu" signal "L7VCC")
		(16 "In7.Cu" signal "L8VCC")
		(18 "In8.Cu" signal "L9GND")
		(20 "In9.Cu" signal "L10")
		(22 "In10.Cu" signal "L11GND")
		(24 "In11.Cu" signal "L12")
		(26 "In12.Cu" signal "L13GND")
		(2 "B.Cu" signal "BOTTOM")
		(9 "F.Adhes" user "F.Adhesive")
		(11 "B.Adhes" user "B.Adhesive")
		(13 "F.Paste" user "Package Geometry/Pastemask Top")
		(15 "B.Paste" user "Package Geometry/Pastemask Bottom")
		(5 "F.SilkS" user "Ref Des/Silkscreen Top")
		(7 "B.SilkS" user "Ref Des/Silkscreen Bottom")
		(1 "F.Mask" user "Board Geometry/Soldermask Top")
		(3 "B.Mask" user "Board Geometry/Soldermask Bottom")
		(17 "Dwgs.User" user "User.Drawings")
		(19 "Cmts.User" user "User.Comments")
		(21 "Eco1.User" user "User.Eco1")
		(23 "Eco2.User" user "User.Eco2")
		(25 "Edge.Cuts" user "Board Geometry/Outline")
		(27 "Margin" user)
		(31 "F.CrtYd" user "Package Geometry/Place Bound Top")
		(29 "B.CrtYd" user "Package Geometry/Place Bound Bottom")
		(35 "F.Fab" user "Ref Des/Assembly Top")
		(33 "B.Fab" user "Ref Des/Assembly Bottom")
	)
	(footprint ""
		(layer "F.Cu")
		(at 352.9838 -99.50323 90)
		(property "Reference" "R7C25"
			(at 0 0 90)
			(layer "F.SilkS")
			(hide yes)
			(effects
				(font
					(size 1.27 1.27)
				)
			)
		)
		(property "Value" ""
			(at 0 0 90)
			(layer "F.Fab")
			(effects
				(font
					(size 1.27 1.27)
				)
			)
		)
		(duplicate_pad_numbers_are_jumpers no)
		(fp_poly
			(pts
				(xy -0.2794 -0.1016) (xy 0.2794 -0.1016) (xy 0.2794 0.9906) (xy -0.2794 0.9906)
			)
			(stroke
				(width 0)
				(type default)
			)
			(fill no)
			(layer "F.CrtYd")
		)
		(fp_line
			(start 0.2794 -0.1016)
			(end -0.2794 -0.1016)
			(stroke
				(width 0.1)
				(type default)
			)
			(layer "F.Fab")
		)
		(fp_line
			(start -0.2794 -0.1016)
			(end -0.2794 0.9906)
			(stroke
				(width 0.1)
				(type default)
			)
			(layer "F.Fab")
		)
		(fp_line
			(start 0.2794 0.9906)
			(end 0.2794 -0.1016)
			(stroke
				(width 0.1)
				(type default)
			)
			(layer "F.Fab")
		)
		(fp_line
			(start -0.2794 0.9906)
			(end 0.2794 0.9906)
			(stroke
				(width 0.1)
				(type default)
			)
			(layer "F.Fab")
		)
		(pad "1" smd rect
			(at 0 0 90)
			(size 0.508 0.508)
			(layers "F.Cu" "F.Mask" "F.Paste")
			(net "VR_PVCCIO_CPU0_OCSET")
		)
		(pad "2" smd rect
			(at 0 0.889 90)
			(size 0.508 0.508)
			(layers "F.Cu" "F.Mask" "F.Paste")
			(net "GND")
		)
		(zone
			(layer "F.Cu")
			(hatch none 0.5)
			(connect_pads
				(clearance 0)
			)
			(min_thickness 0.25)
			(keepout
				(tracks allowed)
				(vias not_allowed)
				(pads allowed)
				(copperpour not_allowed)
				(footprints allowed)
			)
			(placement
				(enabled no)
				(sheetname "")
			)
			(fill
				(thermal_gap 0.5)
				(thermal_bridge_width 0.5)
				(island_removal_mode 0)
			)
			(polygon
				(pts
					(xy 353.2378 -99.24923) (xy 353.2378 -99.75723) (xy 353.6188 -99.75723) (xy 353.6188 -99.24923)
				)
			)
		)
		(zone
			(layer "F.Cu")
			(hatch none 0.5)
			(connect_pads
				(clearance 0)
			)
			(min_thickness 0.25)
			(keepout
				(tracks not_allowed)
				(vias allowed)
				(pads allowed)
				(copperpour not_allowed)
				(footprints allowed)
			)
			(placement
				(enabled no)
				(sheetname "")
			)
			(fill
				(thermal_gap 0.5)
				(thermal_bridge_width 0.5)
				(island_removal_mode 0)
			)
			(polygon
				(pts
					(xy 353.6188 -99.24923) (xy 353.6188 -99.75723) (xy 353.2378 -99.75723) (xy 353.2378 -99.24923)
				)
			)
		)
	)
	(footprint ""
		(layer "F.Cu")
		(at 345.316048 -11.210036 180)
		(property "Reference" "CF16"
			(at 0 0 180)
			(layer "F.SilkS")
			(hide yes)
			(effects
				(font
					(size 1.27 1.27)
				)
			)
		)
		(property "Value" "*"
			(at 1.1811 -2.8194 180)
			(unlocked yes)
			(layer "F.Fab")
			(hide yes)
			(effects
				(font
					(size 1.27 1.016)
					(thickness 0.1524)
				)
			)
		)
		(property "Device Type" "SC22P50V2JN-4GP_SMD-BCG-SC22P5A"
			(at 1.1811 -4.3434 180)
			(unlocked yes)
			(layer "F.Fab")
			(hide yes)
			(effects
				(font
					(size 1.27 1.016)
					(thickness 0.1524)
				)
			)
		)
		(duplicate_pad_numbers_are_jumpers no)
		(fp_rect
			(start -0.4318 0.9525)
			(end 0.4318 -0.9525)
			(stroke
				(width 0)
				(type default)
			)
			(fill no)
			(layer "F.CrtYd")
		)
		(fp_rect
			(start -0.4318 0.9525)
			(end 0.4318 -0.9525)
			(stroke
				(width 0)
				(type default)
			)
			(fill no)
			(layer "F.Fab")
		)
		(pad "1" smd custom
			(at 0 -0.4445 180)
			(size 0.1524 0.1524)
			(layers "F.Cu" "F.Mask" "F.Paste")
			(net "VR_PVDDQ_ABC_AIREF2")
			(options
				(clearance outline)
				(anchor circle)
			)
			(primitives
				(gr_poly
					(pts
						(arc
							(start 0.3048 -0.2032)
							(mid 0.275042 -0.275042)
							(end 0.2032 -0.3048)
						)
						(arc
							(start -0.2032 -0.3048)
							(mid -0.275042 -0.275042)
							(end -0.3048 -0.2032)
						)
						(arc
							(start -0.3048 0.2032)
							(mid -0.275042 0.275042)
							(end -0.2032 0.3048)
						)
						(arc
							(start 0.2032 0.3048)
							(mid 0.275042 0.275042)
							(end 0.3048 0.2032)
						)
					)
					(width 0)
					(fill yes)
				)
			)
		)
		(pad "2" smd custom
			(at 0 0.4445 180)
			(size 0.1524 0.1524)
			(layers "F.Cu" "F.Mask" "F.Paste")
			(net "ISENSE_PVDDQ_ABC_PH2_IMON")
			(options
				(clearance outline)
				(anchor circle)
			)
			(primitives
				(gr_poly
					(pts
						(arc
							(start 0.3048 -0.2032)
							(mid 0.275042 -0.275042)
							(end 0.2032 -0.3048)
						)
						(arc
							(start -0.2032 -0.3048)
							(mid -0.275042 -0.275042)
							(end -0.3048 -0.2032)
						)
						(arc
							(start -0.3048 0.2032)
							(mid -0.275042 0.275042)
							(end -0.2032 0.3048)
						)
						(arc
							(start 0.2032 0.3048)
							(mid 0.275042 0.275042)
							(end 0.3048 0.2032)
						)
					)
					(width 0)
					(fill yes)
				)
			)
		)
	)
	(footprint ""
		(layer "F.Cu")
		(at 338.836 -20.5232 -90)
		(property "Reference" "R7F23"
			(at 0 0 270)
			(layer "F.SilkS")
			(hide yes)
			(effects
				(font
					(size 1.27 1.27)
				)
			)
		)
		(property "Value" ""
			(at 0 0 270)
			(layer "F.Fab")
			(effects
				(font
					(size 1.27 1.27)
				)
			)
		)
		(duplicate_pad_numbers_are_jumpers no)
		(fp_poly
			(pts
				(xy -0.2794 -0.1016) (xy 0.2794 -0.1016) (xy 0.2794 0.9906) (xy -0.2794 0.9906)
			)
			(stroke
				(width 0)
				(type default)
			)
			(fill no)
			(layer "F.CrtYd")
		)
		(fp_line
			(start -0.2794 0.9906)
			(end 0.2794 0.9906)
			(stroke
				(width 0.1)
				(type default)
			)
			(layer "F.Fab")
		)
		(fp_line
			(start 0.2794 0.9906)
			(end 0.2794 -0.1016)
			(stroke
				(width 0.1)
				(type default)
			)
			(layer "F.Fab")
		)
		(fp_line
			(start -0.2794 -0.1016)
			(end -0.2794 0.9906)
			(stroke
				(width 0.1)
				(type default)
			)
			(layer "F.Fab")
		)
		(fp_line
			(start 0.2794 -0.1016)
			(end -0.2794 -0.1016)
			(stroke
				(width 0.1)
				(type default)
			)
			(layer "F.Fab")
		)
		(pad "1" smd rect
			(at 0 0 270)
			(size 0.508 0.508)
			(layers "F.Cu" "F.Mask" "F.Paste")
			(net "IRQ_PVDDQ_ABC_VRHOT_LVT3_R_N")
		)
		(pad "2" smd rect
			(at 0 0.889 270)
			(size 0.508 0.508)
			(layers "F.Cu" "F.Mask" "F.Paste")
			(net "IRQ_PVDDQ_ABC_VRHOT_LVT3_N")
		)
		(zone
			(layer "F.Cu")
			(hatch none 0.5)
			(connect_pads
				(clearance 0)
			)
			(min_thickness 0.25)
			(keepout
				(tracks not_allowed)
				(vias allowed)
				(pads allowed)
				(copperpour not_allowed)
				(footprints allowed)
			)
			(placement
				(enabled no)
				(sheetname "")
			)
			(fill
				(thermal_gap 0.5)
				(thermal_bridge_width 0.5)
				(island_removal_mode 0)
			)
			(polygon
				(pts
					(xy 338.201 -20.7772) (xy 338.201 -20.2692) (xy 338.582 -20.2692) (xy 338.582 -20.7772)
				)
			)
		)
		(zone
			(layer "F.Cu")
			(hatch none 0.5)
			(connect_pads
				(clearance 0)
			)
			(min_thickness 0.25)
			(keepout
				(tracks allowed)
				(vias not_allowed)
				(pads allowed)
				(copperpour not_allowed)
				(footprints allowed)
			)
			(placement
				(enabled no)
				(sheetname "")
			)
			(fill
				(thermal_gap 0.5)
				(thermal_bridge_width 0.5)
				(island_removal_mode 0)
			)
			(polygon
				(pts
					(xy 338.582 -20.7772) (xy 338.582 -20.2692) (xy 338.201 -20.2692) (xy 338.201 -20.7772)
				)
			)
		)
	)
)
